(kicad_pcb
	(version 20241229)
	(generator "pcbnew")
	(generator_version "9.0")
	(general
		(thickness 1.294)
		(legacy_teardrops no)
	)
	(paper "A3")
	(title_block
		(title "Kintex 410T devboard")
		(date "2024-04-03")
		(rev "1.1.2")
		(comment 9 "footprints 626-631 of 975")
	)
	(layers
		(0 "F.Cu" mixed)
		(4 "In1.Cu" power)
		(6 "In2.Cu" power)
		(8 "In3.Cu" mixed)
		(10 "In4.Cu" power)
		(12 "In5.Cu" mixed)
		(14 "In6.Cu" power)
		(16 "In7.Cu" mixed)
		(18 "In8.Cu" power)
		(2 "B.Cu" mixed)
		(9 "F.Adhes" user "F.Adhesive")
		(11 "B.Adhes" user "B.Adhesive")
		(13 "F.Paste" user)
		(15 "B.Paste" user)
		(5 "F.SilkS" user "F.Silkscreen")
		(7 "B.SilkS" user "B.Silkscreen")
		(1 "F.Mask" user)
		(3 "B.Mask" user)
		(17 "Dwgs.User" user "User.Drawings")
		(19 "Cmts.User" user "User.Comments")
		(21 "Eco1.User" user "User.Eco1")
		(23 "Eco2.User" user "User.Eco2")
		(25 "Edge.Cuts" user)
		(27 "Margin" user)
		(31 "F.CrtYd" user "F.Courtyard")
		(29 "B.CrtYd" user "B.Courtyard")
		(35 "F.Fab" user)
		(33 "B.Fab" user)
	)
	(footprint "antmicro-footprints:R_0402_1005Metric"
		(layer "B.Cu")
		(at 233.8 147.9)
		(descr "Resistor SMD 0402")
		(tags "resistor SMD 0402")
		(property "Reference" "R194"
			(at -0.7 0.375 180)
			(layer "B.SilkS")
			(effects
				(font
					(size 0.7 0.7)
					(thickness 0.15)
				)
				(justify left bottom mirror)
			)
		)
		(property "Value" "R_10k_0402"
			(at 0 -1.4 180)
			(layer "B.Fab")
			(effects
				(font
					(size 0.7 0.7)
					(thickness 0.15)
				)
				(justify left bottom mirror)
			)
		)
		(property "Description" "SMD Chip Resistor, 10 kohm, ± 1%, 62.5 mW, 0402 [1005 Metric], Thick Film, General Purpose"
			(at 0 0 0)
			(layer "F.Fab")
			(hide yes)
			(effects
				(font
					(size 1.27 1.27)
					(thickness 0.15)
				)
			)
		)
		(property "Author" "Antmicro"
			(at 0 0 0)
			(layer "B.Fab")
			(hide yes)
			(effects
				(font
					(size 1 1)
					(thickness 0.15)
				)
				(justify mirror)
			)
		)
		(property "License" "Apache-2.0"
			(at 0 0 0)
			(layer "B.Fab")
			(hide yes)
			(effects
				(font
					(size 1 1)
					(thickness 0.15)
				)
				(justify mirror)
			)
		)
		(property "MPN" "CR0402-FX-1002GLF"
			(at 0 0 0)
			(layer "B.Fab")
			(hide yes)
			(effects
				(font
					(size 1 1)
					(thickness 0.15)
				)
				(justify mirror)
			)
		)
		(property "Manufacturer" "Bourns"
			(at 0 0 0)
			(layer "B.Fab")
			(hide yes)
			(effects
				(font
					(size 1 1)
					(thickness 0.15)
				)
				(justify mirror)
			)
		)
		(property "Tolerance" "1%"
			(at 0 0 0)
			(layer "B.Fab")
			(hide yes)
			(effects
				(font
					(size 1 1)
					(thickness 0.15)
				)
				(justify mirror)
			)
		)
		(property "Val" "10k"
			(at 0 0 0)
			(layer "B.Fab")
			(hide yes)
			(effects
				(font
					(size 1 1)
					(thickness 0.15)
				)
				(justify mirror)
			)
		)
		(sheetname "USB PHY")
		(sheetfile "usb-phy.kicad_sch")
		(attr smd)
		(fp_rect
			(start -0.925 0.47)
			(end 0.925 -0.47)
			(stroke
				(width 0.05)
				(type default)
			)
			(fill no)
			(layer "B.CrtYd")
		)
		(fp_rect
			(start -0.5 0.25)
			(end 0.5 -0.25)
			(stroke
				(width 0.15)
				(type solid)
			)
			(fill no)
			(layer "B.Fab")
		)
		(pad "1" smd roundrect
			(at -0.48 0)
			(size 0.59 0.64)
			(layers "B.Cu" "B.Mask" "B.Paste")
			(roundrect_rratio 0.25)
			(net 498 "/FPGA Bank 12 & 13/USB_USER.~{OE}")
			(pintype "passive")
		)
		(pad "2" smd roundrect
			(at 0.48 0)
			(size 0.59 0.64)
			(layers "B.Cu" "B.Mask" "B.Paste")
			(roundrect_rratio 0.25)
			(net 26 "+1V8")
			(pintype "passive")
		)
	)
	(footprint "antmicro-footprints:R_0402_1005Metric"
		(layer "B.Cu")
		(at 221.084 146.2 -90)
		(descr "Resistor SMD 0402")
		(tags "resistor SMD 0402")
		(property "Reference" "R235"
			(at -3.625 -0.375 90)
			(layer "B.SilkS")
			(effects
				(font
					(size 0.7 0.7)
					(thickness 0.15)
				)
				(justify left bottom mirror)
			)
		)
		(property "Value" "R_10R_0402"
			(at 0 -1.4 90)
			(layer "B.Fab")
			(effects
				(font
					(size 0.7 0.7)
					(thickness 0.15)
				)
				(justify left bottom mirror)
			)
		)
		(property "Description" "SMD Chip Resistor, 10 ohm, ± 1%, 62.5 mW, 0402 [1005 Metric], Thick Film, General Purpose"
			(at 0 0 270)
			(layer "F.Fab")
			(hide yes)
			(effects
				(font
					(size 1.27 1.27)
					(thickness 0.15)
				)
			)
		)
		(property "Author" "Antmicro"
			(at 74.884 367.284 0)
			(layer "B.Fab")
			(hide yes)
			(effects
				(font
					(size 1 1)
					(thickness 0.15)
				)
				(justify mirror)
			)
		)
		(property "License" "Apache-2.0"
			(at 74.884 367.284 0)
			(layer "B.Fab")
			(hide yes)
			(effects
				(font
					(size 1 1)
					(thickness 0.15)
				)
				(justify mirror)
			)
		)
		(property "MPN" "CR0402-FX-10R0GLF"
			(at 74.884 367.284 0)
			(layer "B.Fab")
			(hide yes)
			(effects
				(font
					(size 1 1)
					(thickness 0.15)
				)
				(justify mirror)
			)
		)
		(property "Manufacturer" "Bourns"
			(at 74.884 367.284 0)
			(layer "B.Fab")
			(hide yes)
			(effects
				(font
					(size 1 1)
					(thickness 0.15)
				)
				(justify mirror)
			)
		)
		(property "Tolerance" "1%"
			(at 74.884 367.284 0)
			(layer "B.Fab")
			(hide yes)
			(effects
				(font
					(size 1 1)
					(thickness 0.15)
				)
				(justify mirror)
			)
		)
		(property "Val" "10R"
			(at 74.884 367.284 0)
			(layer "B.Fab")
			(hide yes)
			(effects
				(font
					(size 1 1)
					(thickness 0.15)
				)
				(justify mirror)
			)
		)
		(sheetname "HDMI + Ethernet")
		(sheetfile "hdmi-ethernet.kicad_sch")
		(attr smd)
		(fp_rect
			(start -0.925 0.47)
			(end 0.925 -0.47)
			(stroke
				(width 0.05)
				(type default)
			)
			(fill no)
			(layer "B.CrtYd")
		)
		(fp_rect
			(start -0.5 0.25)
			(end 0.5 -0.25)
			(stroke
				(width 0.15)
				(type solid)
			)
			(fill no)
			(layer "B.Fab")
		)
		(pad "1" smd roundrect
			(at -0.48 0 270)
			(size 0.59 0.64)
			(layers "B.Cu" "B.Mask" "B.Paste")
			(roundrect_rratio 0.25)
			(net 517 "/FPGA Bank 18 & 32/ETH_RMII.RX_DV")
			(pintype "passive")
		)
		(pad "2" smd roundrect
			(at 0.48 0 270)
			(size 0.59 0.64)
			(layers "B.Cu" "B.Mask" "B.Paste")
			(roundrect_rratio 0.25)
			(net 944 "/HDMI + Ethernet/ETH_PHY_RX_DV")
			(pintype "passive")
		)
	)
	(footprint "antmicro-footprints:C_0402_1005Metric"
		(layer "B.Cu")
		(at 198.01 122.5)
		(descr "Capacitor SMD 0402")
		(tags "capacitor SMD 0402")
		(property "Reference" "C82"
			(at 25.075 -29.575 180)
			(layer "B.SilkS")
			(effects
				(font
					(size 0.7 0.7)
					(thickness 0.15)
				)
				(justify left bottom mirror)
			)
		)
		(property "Value" "C_100n_0402"
			(at 0 -1.169 180)
			(layer "B.Fab")
			(effects
				(font
					(size 0.7 0.7)
					(thickness 0.15)
				)
				(justify left bottom mirror)
			)
		)
		(property "Description" "SMD Multilayer Ceramic Capacitor, 0.1 µF, 50 V, 0402 [1005 Metric], ± 10%, X5R, GRM Series"
			(at 0 0 0)
			(layer "F.Fab")
			(hide yes)
			(effects
				(font
					(size 1.27 1.27)
					(thickness 0.15)
				)
			)
		)
		(property "Author" "Antmicro"
			(at 0 0 0)
			(layer "B.Fab")
			(hide yes)
			(effects
				(font
					(size 1 1)
					(thickness 0.15)
				)
				(justify mirror)
			)
		)
		(property "Dielectric" "X5R"
			(at 0 0 0)
			(layer "B.Fab")
			(hide yes)
			(effects
				(font
					(size 1 1)
					(thickness 0.15)
				)
				(justify mirror)
			)
		)
		(property "License" "Apache-2.0"
			(at 0 0 0)
			(layer "B.Fab")
			(hide yes)
			(effects
				(font
					(size 1 1)
					(thickness 0.15)
				)
				(justify mirror)
			)
		)
		(property "MPN" "GRM155R61H104KE14D"
			(at 0 0 0)
			(layer "B.Fab")
			(hide yes)
			(effects
				(font
					(size 1 1)
					(thickness 0.15)
				)
				(justify mirror)
			)
		)
		(property "Manufacturer" "Murata"
			(at 0 0 0)
			(layer "B.Fab")
			(hide yes)
			(effects
				(font
					(size 1 1)
					(thickness 0.15)
				)
				(justify mirror)
			)
		)
		(property "Val" "100n"
			(at 0 0 0)
			(layer "B.Fab")
			(hide yes)
			(effects
				(font
					(size 1 1)
					(thickness 0.15)
				)
				(justify mirror)
			)
		)
		(property "Voltage" "50V"
			(at 0 0 0)
			(layer "B.Fab")
			(hide yes)
			(effects
				(font
					(size 1 1)
					(thickness 0.15)
				)
				(justify mirror)
			)
		)
		(sheetname "FPGA Bank 18 & 32")
		(sheetfile "fpga-bank-18-32.kicad_sch")
		(attr smd)
		(fp_rect
			(start -0.925 0.47)
			(end 0.925 -0.47)
			(stroke
				(width 0.05)
				(type default)
			)
			(fill no)
			(layer "B.CrtYd")
		)
		(fp_line
			(start -0.494 -0.248)
			(end -0.494 0.25)
			(stroke
				(width 0.15)
				(type solid)
			)
			(layer "B.Fab")
		)
		(fp_line
			(start -0.494 0.25)
			(end 0.504 0.25)
			(stroke
				(width 0.15)
				(type solid)
			)
			(layer "B.Fab")
		)
		(fp_line
			(start 0.504 -0.248)
			(end -0.494 -0.248)
			(stroke
				(width 0.15)
				(type solid)
			)
			(layer "B.Fab")
		)
		(fp_line
			(start 0.504 0.25)
			(end 0.504 -0.248)
			(stroke
				(width 0.15)
				(type solid)
			)
			(layer "B.Fab")
		)
		(pad "1" smd roundrect
			(at -0.48 0)
			(size 0.59 0.64)
			(layers "B.Cu" "B.Mask" "B.Paste")
			(roundrect_rratio 0.25)
			(net 1 "GND")
			(pintype "passive")
		)
		(pad "2" smd roundrect
			(at 0.48 0)
			(size 0.59 0.64)
			(layers "B.Cu" "B.Mask" "B.Paste")
			(roundrect_rratio 0.25)
			(net 24 "+3V3")
			(pintype "passive")
		)
	)
	(footprint "antmicro-footprints:C_0402_1005Metric"
		(layer "B.Cu")
		(at 244.701 165)
		(descr "Capacitor SMD 0402")
		(tags "capacitor SMD 0402")
		(property "Reference" "C269"
			(at 1.374 2.275 0)
			(layer "B.SilkS")
			(effects
				(font
					(size 0.7 0.7)
					(thickness 0.15)
				)
				(justify left bottom mirror)
			)
		)
		(property "Value" "C_100n_0402"
			(at 0 -1.169 180)
			(layer "B.Fab")
			(effects
				(font
					(size 0.7 0.7)
					(thickness 0.15)
				)
				(justify left bottom mirror)
			)
		)
		(property "Description" "SMD Multilayer Ceramic Capacitor, 0.1 µF, 50 V, 0402 [1005 Metric], ± 10%, X5R, GRM Series"
			(at 0 0 0)
			(layer "F.Fab")
			(hide yes)
			(effects
				(font
					(size 1.27 1.27)
					(thickness 0.15)
				)
			)
		)
		(property "Author" "Antmicro"
			(at 0 0 0)
			(layer "B.Fab")
			(hide yes)
			(effects
				(font
					(size 1 1)
					(thickness 0.15)
				)
				(justify mirror)
			)
		)
		(property "Dielectric" "X5R"
			(at 0 0 0)
			(layer "B.Fab")
			(hide yes)
			(effects
				(font
					(size 1 1)
					(thickness 0.15)
				)
				(justify mirror)
			)
		)
		(property "License" "Apache-2.0"
			(at 0 0 0)
			(layer "B.Fab")
			(hide yes)
			(effects
				(font
					(size 1 1)
					(thickness 0.15)
				)
				(justify mirror)
			)
		)
		(property "MPN" "GRM155R61H104KE14D"
			(at 0 0 0)
			(layer "B.Fab")
			(hide yes)
			(effects
				(font
					(size 1 1)
					(thickness 0.15)
				)
				(justify mirror)
			)
		)
		(property "Manufacturer" "Murata"
			(at 0 0 0)
			(layer "B.Fab")
			(hide yes)
			(effects
				(font
					(size 1 1)
					(thickness 0.15)
				)
				(justify mirror)
			)
		)
		(property "Val" "100n"
			(at 0 0 0)
			(layer "B.Fab")
			(hide yes)
			(effects
				(font
					(size 1 1)
					(thickness 0.15)
				)
				(justify mirror)
			)
		)
		(property "Voltage" "50V"
			(at 0 0 0)
			(layer "B.Fab")
			(hide yes)
			(effects
				(font
					(size 1 1)
					(thickness 0.15)
				)
				(justify mirror)
			)
		)
		(sheetname "HDMI + Ethernet")
		(sheetfile "hdmi-ethernet.kicad_sch")
		(attr smd)
		(fp_rect
			(start -0.925 0.47)
			(end 0.925 -0.47)
			(stroke
				(width 0.05)
				(type default)
			)
			(fill no)
			(layer "B.CrtYd")
		)
		(fp_line
			(start -0.494 -0.248)
			(end -0.494 0.25)
			(stroke
				(width 0.15)
				(type solid)
			)
			(layer "B.Fab")
		)
		(fp_line
			(start -0.494 0.25)
			(end 0.504 0.25)
			(stroke
				(width 0.15)
				(type solid)
			)
			(layer "B.Fab")
		)
		(fp_line
			(start 0.504 -0.248)
			(end -0.494 -0.248)
			(stroke
				(width 0.15)
				(type solid)
			)
			(layer "B.Fab")
		)
		(fp_line
			(start 0.504 0.25)
			(end 0.504 -0.248)
			(stroke
				(width 0.15)
				(type solid)
			)
			(layer "B.Fab")
		)
		(pad "1" smd roundrect
			(at -0.48 0)
			(size 0.59 0.64)
			(layers "B.Cu" "B.Mask" "B.Paste")
			(roundrect_rratio 0.25)
			(net 1 "GND")
			(pintype "passive")
		)
		(pad "2" smd roundrect
			(at 0.48 0)
			(size 0.59 0.64)
			(layers "B.Cu" "B.Mask" "B.Paste")
			(roundrect_rratio 0.25)
			(net 12 "Net-(J15A-TRDCT1{slash}2{slash}3{slash}4_1)")
			(pintype "passive")
		)
	)
	(footprint "antmicro-footprints:C_0402_1005Metric"
		(layer "B.Cu")
		(at 196.85 132.225 180)
		(descr "Capacitor SMD 0402")
		(tags "capacitor SMD 0402")
		(property "Reference" "C117"
			(at -25.35 28.05 0)
			(layer "B.SilkS")
			(effects
				(font
					(size 0.7 0.7)
					(thickness 0.15)
				)
				(justify left bottom mirror)
			)
		)
		(property "Value" "C_100n_0402"
			(at 0 -1.169 0)
			(layer "B.Fab")
			(effects
				(font
					(size 0.7 0.7)
					(thickness 0.15)
				)
				(justify left bottom mirror)
			)
		)
		(property "Description" "SMD Multilayer Ceramic Capacitor, 0.1 µF, 50 V, 0402 [1005 Metric], ± 10%, X5R, GRM Series"
			(at 0 0 180)
			(layer "F.Fab")
			(hide yes)
			(effects
				(font
					(size 1.27 1.27)
					(thickness 0.15)
				)
			)
		)
		(property "Author" "Antmicro"
			(at 393.7 264.45 0)
			(layer "B.Fab")
			(hide yes)
			(effects
				(font
					(size 1 1)
					(thickness 0.15)
				)
				(justify mirror)
			)
		)
		(property "Dielectric" "X5R"
			(at 393.7 264.45 0)
			(layer "B.Fab")
			(hide yes)
			(effects
				(font
					(size 1 1)
					(thickness 0.15)
				)
				(justify mirror)
			)
		)
		(property "License" "Apache-2.0"
			(at 393.7 264.45 0)
			(layer "B.Fab")
			(hide yes)
			(effects
				(font
					(size 1 1)
					(thickness 0.15)
				)
				(justify mirror)
			)
		)
		(property "MPN" "GRM155R61H104KE14D"
			(at 393.7 264.45 0)
			(layer "B.Fab")
			(hide yes)
			(effects
				(font
					(size 1 1)
					(thickness 0.15)
				)
				(justify mirror)
			)
		)
		(property "Manufacturer" "Murata"
			(at 393.7 264.45 0)
			(layer "B.Fab")
			(hide yes)
			(effects
				(font
					(size 1 1)
					(thickness 0.15)
				)
				(justify mirror)
			)
		)
		(property "Val" "100n"
			(at 393.7 264.45 0)
			(layer "B.Fab")
			(hide yes)
			(effects
				(font
					(size 1 1)
					(thickness 0.15)
				)
				(justify mirror)
			)
		)
		(property "Voltage" "50V"
			(at 393.7 264.45 0)
			(layer "B.Fab")
			(hide yes)
			(effects
				(font
					(size 1 1)
					(thickness 0.15)
				)
				(justify mirror)
			)
		)
		(sheetname "FPGA supply")
		(sheetfile "fpga-supply.kicad_sch")
		(attr smd)
		(fp_rect
			(start -0.925 0.47)
			(end 0.925 -0.47)
			(stroke
				(width 0.05)
				(type default)
			)
			(fill no)
			(layer "B.CrtYd")
		)
		(fp_line
			(start 0.504 0.25)
			(end 0.504 -0.248)
			(stroke
				(width 0.15)
				(type solid)
			)
			(layer "B.Fab")
		)
		(fp_line
			(start 0.504 -0.248)
			(end -0.494 -0.248)
			(stroke
				(width 0.15)
				(type solid)
			)
			(layer "B.Fab")
		)
		(fp_line
			(start -0.494 0.25)
			(end 0.504 0.25)
			(stroke
				(width 0.15)
				(type solid)
			)
			(layer "B.Fab")
		)
		(fp_line
			(start -0.494 -0.248)
			(end -0.494 0.25)
			(stroke
				(width 0.15)
				(type solid)
			)
			(layer "B.Fab")
		)
		(pad "1" smd roundrect
			(at -0.48 0 180)
			(size 0.59 0.64)
			(layers "B.Cu" "B.Mask" "B.Paste")
			(roundrect_rratio 0.25)
			(net 1 "GND")
			(pintype "passive")
		)
		(pad "2" smd roundrect
			(at 0.48 0 180)
			(size 0.59 0.64)
			(layers "B.Cu" "B.Mask" "B.Paste")
			(roundrect_rratio 0.25)
			(net 650 "+1V0")
			(pintype "passive")
		)
	)
	(footprint "antmicro-footprints:C_0402_1005Metric"
		(layer "B.Cu")
		(at 196.325 126.825 180)
		(descr "Capacitor SMD 0402")
		(tags "capacitor SMD 0402")
		(property "Reference" "C128"
			(at -25.35 29.325 0)
			(layer "B.SilkS")
			(effects
				(font
					(size 0.7 0.7)
					(thickness 0.15)
				)
				(justify left bottom mirror)
			)
		)
		(property "Value" "C_100n_0402"
			(at 0 -1.169 0)
			(layer "B.Fab")
			(effects
				(font
					(size 0.7 0.7)
					(thickness 0.15)
				)
				(justify left bottom mirror)
			)
		)
		(property "Description" "SMD Multilayer Ceramic Capacitor, 0.1 µF, 50 V, 0402 [1005 Metric], ± 10%, X5R, GRM Series"
			(at 0 0 180)
			(layer "F.Fab")
			(hide yes)
			(effects
				(font
					(size 1.27 1.27)
					(thickness 0.15)
				)
			)
		)
		(property "Author" "Antmicro"
			(at 392.65 253.65 0)
			(layer "B.Fab")
			(hide yes)
			(effects
				(font
					(size 1 1)
					(thickness 0.15)
				)
				(justify mirror)
			)
		)
		(property "Dielectric" "X5R"
			(at 392.65 253.65 0)
			(layer "B.Fab")
			(hide yes)
			(effects
				(font
					(size 1 1)
					(thickness 0.15)
				)
				(justify mirror)
			)
		)
		(property "License" "Apache-2.0"
			(at 392.65 253.65 0)
			(layer "B.Fab")
			(hide yes)
			(effects
				(font
					(size 1 1)
					(thickness 0.15)
				)
				(justify mirror)
			)
		)
		(property "MPN" "GRM155R61H104KE14D"
			(at 392.65 253.65 0)
			(layer "B.Fab")
			(hide yes)
			(effects
				(font
					(size 1 1)
					(thickness 0.15)
				)
				(justify mirror)
			)
		)
		(property "Manufacturer" "Murata"
			(at 392.65 253.65 0)
			(layer "B.Fab")
			(hide yes)
			(effects
				(font
					(size 1 1)
					(thickness 0.15)
				)
				(justify mirror)
			)
		)
		(property "Val" "100n"
			(at 392.65 253.65 0)
			(layer "B.Fab")
			(hide yes)
			(effects
				(font
					(size 1 1)
					(thickness 0.15)
				)
				(justify mirror)
			)
		)
		(property "Voltage" "50V"
			(at 392.65 253.65 0)
			(layer "B.Fab")
			(hide yes)
			(effects
				(font
					(size 1 1)
					(thickness 0.15)
				)
				(justify mirror)
			)
		)
		(sheetname "FPGA supply")
		(sheetfile "fpga-supply.kicad_sch")
		(attr smd)
		(fp_rect
			(start -0.925 0.47)
			(end 0.925 -0.47)
			(stroke
				(width 0.05)
				(type default)
			)
			(fill no)
			(layer "B.CrtYd")
		)
		(fp_line
			(start 0.504 0.25)
			(end 0.504 -0.248)
			(stroke
				(width 0.15)
				(type solid)
			)
			(layer "B.Fab")
		)
		(fp_line
			(start 0.504 -0.248)
			(end -0.494 -0.248)
			(stroke
				(width 0.15)
				(type solid)
			)
			(layer "B.Fab")
		)
		(fp_line
			(start -0.494 0.25)
			(end 0.504 0.25)
			(stroke
				(width 0.15)
				(type solid)
			)
			(layer "B.Fab")
		)
		(fp_line
			(start -0.494 -0.248)
			(end -0.494 0.25)
			(stroke
				(width 0.15)
				(type solid)
			)
			(layer "B.Fab")
		)
		(pad "1" smd roundrect
			(at -0.48 0 180)
			(size 0.59 0.64)
			(layers "B.Cu" "B.Mask" "B.Paste")
			(roundrect_rratio 0.25)
			(net 1 "GND")
			(pintype "passive")
		)
		(pad "2" smd roundrect
			(at 0.48 0 180)
			(size 0.59 0.64)
			(layers "B.Cu" "B.Mask" "B.Paste")
			(roundrect_rratio 0.25)
			(net 650 "+1V0")
			(pintype "passive")
		)
	)
)
